FILE_TYPE=LIBRARY_PARTS;
TIME=' Created/Modified on Thu Nov 29 16:21:18 2007' ;
primitive 'Q_DIODE';
  pin
    '1':
      PIN_NUMBER='(1)';
      INPUT_LOAD='(-0.01,0.01)';
      OUTPUT_LOAD='(1.0,-1.0)';
      BIDIRECTIONAL='TRUE';
    '2':
      PIN_NUMBER='(2)';
      INPUT_LOAD='(-0.01,0.01)';
      OUTPUT_LOAD='(1.0,-1.0)';
      BIDIRECTIONAL='TRUE';
  end_pin;
  body
    CLASS='DISCRETE';
    PART_NAME='Q_DIODE';
    PHYS_DES_PREFIX='D';
  end_body;
end_primitive;
END.
